(kicad_pcb
	(version 20240108)
	(generator "pcbnew")
	(generator_version "8.0")
	(general
		(thickness 1.62)
		(legacy_teardrops no)
	)
	(paper "A4")
	(title_block
		(title "Jetson Orin Baseboard")
		(date "2025-03-12")
		(rev "1.3.4")
		(company "Antmicro Ltd")
		(comment 1 "www.antmicro.com")
		(comment 9 "footprints 346-350 of 677")
	)
	(layers
		(0 "F.Cu" signal)
		(1 "In1.Cu" signal)
		(2 "In2.Cu" signal)
		(3 "In3.Cu" signal)
		(4 "In4.Cu" jumper)
		(5 "In5.Cu" signal)
		(6 "In6.Cu" signal)
		(31 "B.Cu" signal)
		(32 "B.Adhes" user "B.Adhesive")
		(33 "F.Adhes" user "F.Adhesive")
		(34 "B.Paste" user)
		(35 "F.Paste" user)
		(36 "B.SilkS" user "B.Silkscreen")
		(37 "F.SilkS" user "F.Silkscreen")
		(38 "B.Mask" user)
		(39 "F.Mask" user)
		(40 "Dwgs.User" user "User.Drawings")
		(41 "Cmts.User" user "User.Comments")
		(42 "Eco1.User" user "User.Eco1")
		(43 "Eco2.User" user "User.Eco2")
		(44 "Edge.Cuts" user)
		(45 "Margin" user)
		(46 "B.CrtYd" user "B.Courtyard")
		(47 "F.CrtYd" user "F.Courtyard")
		(48 "B.Fab" user)
		(49 "F.Fab" user)
	)
	(footprint "antmicro-footprints:R_0402_1005Metric"
		(layer "B.Cu")
		(at 109 85.42)
		(descr "Resistor SMD 0402")
		(tags "resistor SMD 0402")
		(property "Reference" "R17"
			(at 1 -0.42 180)
			(layer "B.SilkS")
			(effects
				(font
					(size 0.7 0.7)
					(thickness 0.15)
				)
				(justify left bottom mirror)
			)
		)
		(property "Value" "R_0R_0402"
			(at 0 -1.4 180)
			(layer "B.Fab")
			(effects
				(font
					(size 0.7 0.7)
					(thickness 0.15)
				)
				(justify left bottom mirror)
			)
		)
		(property "Footprint" "antmicro-footprints:R_0402_1005Metric"
			(at 0 0 0)
			(layer "F.Fab")
			(hide yes)
			(effects
				(font
					(size 1.27 1.27)
					(thickness 0.15)
				)
			)
		)
		(property "Datasheet" "https://industrial.panasonic.com/cdbs/www-data/pdf/RDA0000/AOA0000C301.pdf"
			(at 0 0 0)
			(layer "F.Fab")
			(hide yes)
			(effects
				(font
					(size 1.27 1.27)
					(thickness 0.15)
				)
			)
		)
		(property "Author" "Antmicro"
			(at 0 0 0)
			(layer "B.Fab")
			(hide yes)
			(effects
				(font
					(size 1 1)
					(thickness 0.15)
				)
				(justify mirror)
			)
		)
		(property "Current" "1A"
			(at 0 0 0)
			(layer "B.Fab")
			(hide yes)
			(effects
				(font
					(size 1 1)
					(thickness 0.15)
				)
				(justify mirror)
			)
		)
		(property "License" "Apache-2.0"
			(at 0 0 0)
			(layer "B.Fab")
			(hide yes)
			(effects
				(font
					(size 1 1)
					(thickness 0.15)
				)
				(justify mirror)
			)
		)
		(property "MPN" "ERJ2GE0R00X"
			(at 0 0 0)
			(layer "B.Fab")
			(hide yes)
			(effects
				(font
					(size 1 1)
					(thickness 0.15)
				)
				(justify mirror)
			)
		)
		(property "Manufacturer" "Panasonic"
			(at 0 0 0)
			(layer "B.Fab")
			(hide yes)
			(effects
				(font
					(size 1 1)
					(thickness 0.15)
				)
				(justify mirror)
			)
		)
		(property "Tolerance" ""
			(at 0 0 0)
			(layer "B.Fab")
			(hide yes)
			(effects
				(font
					(size 1 1)
					(thickness 0.15)
				)
				(justify mirror)
			)
		)
		(property "Val" "0R"
			(at 0 0 0)
			(layer "B.Fab")
			(hide yes)
			(effects
				(font
					(size 1 1)
					(thickness 0.15)
				)
				(justify mirror)
			)
		)
		(sheetname "M.2")
		(sheetfile "m-2.kicad_sch")
		(attr smd)
		(fp_rect
			(start -0.925 0.47)
			(end 0.925 -0.47)
			(stroke
				(width 0.05)
				(type default)
			)
			(fill none)
			(layer "B.CrtYd")
		)
		(fp_rect
			(start -0.5 0.25)
			(end 0.5 -0.25)
			(stroke
				(width 0.15)
				(type solid)
			)
			(fill none)
			(layer "B.Fab")
		)
		(fp_text user "License: Apache-2.0"
			(at -0.95 -5.169 180)
			(layer "B.Fab")
			(hide yes)
			(effects
				(font
					(size 0.7 0.7)
					(thickness 0.15)
				)
				(justify left bottom mirror)
			)
		)
		(fp_text user "${REFERENCE}"
			(at -0.95 -3.168 180)
			(layer "B.Fab")
			(hide yes)
			(effects
				(font
					(size 0.7 0.7)
					(thickness 0.15)
				)
				(justify left bottom mirror)
			)
		)
		(fp_text user "Author: Antmicro"
			(at -0.95 -4.169 180)
			(layer "B.Fab")
			(hide yes)
			(effects
				(font
					(size 0.7 0.7)
					(thickness 0.15)
				)
				(justify left bottom mirror)
			)
		)
		(pad "1" smd roundrect
			(at -0.48 0)
			(size 0.59 0.64)
			(layers "B.Cu" "B.Paste" "B.Mask")
			(roundrect_rratio 0.25)
			(net 454 "PCIE0_CLKREQ*")
			(pintype "passive")
		)
		(pad "2" smd roundrect
			(at 0.48 0)
			(size 0.59 0.64)
			(layers "B.Cu" "B.Paste" "B.Mask")
			(roundrect_rratio 0.25)
			(net 248 "/M.2/~{M2_M_CLKREQ0}")
			(pintype "passive")
		)
	)
	(footprint "antmicro-footprints:C_0603_1608Metric"
		(layer "B.Cu")
		(at 114.5 91.5 180)
		(descr "Capacitor SMD 0603")
		(tags "capacitor 0603")
		(property "Reference" "C22"
			(at -1.1 0.6 0)
			(layer "B.SilkS")
			(effects
				(font
					(size 0.7 0.7)
					(thickness 0.15)
				)
				(justify left bottom mirror)
			)
		)
		(property "Value" "C_10u_0603"
			(at 0 -1.6 0)
			(layer "B.Fab")
			(effects
				(font
					(size 0.7 0.7)
					(thickness 0.15)
				)
				(justify left bottom mirror)
			)
		)
		(property "Footprint" "antmicro-footprints:C_0603_1608Metric"
			(at 0 0 180)
			(layer "F.Fab")
			(hide yes)
			(effects
				(font
					(size 1.27 1.27)
					(thickness 0.15)
				)
			)
		)
		(property "Datasheet" "https://www.murata.com/products/productdetail?partno=GRM188R61A106KE69%23"
			(at 0 0 180)
			(layer "F.Fab")
			(hide yes)
			(effects
				(font
					(size 1.27 1.27)
					(thickness 0.15)
				)
			)
		)
		(property "Author" "Antmicro"
			(at 229 183 0)
			(layer "B.Fab")
			(hide yes)
			(effects
				(font
					(size 1 1)
					(thickness 0.15)
				)
				(justify mirror)
			)
		)
		(property "Dielectric" "template_dielectric"
			(at 229 183 0)
			(layer "B.Fab")
			(hide yes)
			(effects
				(font
					(size 1 1)
					(thickness 0.15)
				)
				(justify mirror)
			)
		)
		(property "License" "Apache-2.0"
			(at 229 183 0)
			(layer "B.Fab")
			(hide yes)
			(effects
				(font
					(size 1 1)
					(thickness 0.15)
				)
				(justify mirror)
			)
		)
		(property "MPN" "GRM188R61A106KE69D"
			(at 229 183 0)
			(layer "B.Fab")
			(hide yes)
			(effects
				(font
					(size 1 1)
					(thickness 0.15)
				)
				(justify mirror)
			)
		)
		(property "Manufacturer" "Murata"
			(at 229 183 0)
			(layer "B.Fab")
			(hide yes)
			(effects
				(font
					(size 1 1)
					(thickness 0.15)
				)
				(justify mirror)
			)
		)
		(property "Val" "10u"
			(at 229 183 0)
			(layer "B.Fab")
			(hide yes)
			(effects
				(font
					(size 1 1)
					(thickness 0.15)
				)
				(justify mirror)
			)
		)
		(property "Voltage" ""
			(at 229 183 0)
			(layer "B.Fab")
			(hide yes)
			(effects
				(font
					(size 1 1)
					(thickness 0.15)
				)
				(justify mirror)
			)
		)
		(sheetname "M.2")
		(sheetfile "m-2.kicad_sch")
		(attr smd)
		(fp_line
			(start 0.15 0.4)
			(end -0.15 0.4)
			(stroke
				(width 0.15)
				(type solid)
			)
			(layer "B.SilkS")
		)
		(fp_line
			(start 0.15 -0.4)
			(end -0.15 -0.4)
			(stroke
				(width 0.15)
				(type solid)
			)
			(layer "B.SilkS")
		)
		(fp_rect
			(start -1.25 0.65)
			(end 1.25 -0.65)
			(stroke
				(width 0.05)
				(type solid)
			)
			(fill none)
			(layer "B.CrtYd")
		)
		(fp_rect
			(start -0.8 0.4)
			(end 0.8 -0.4)
			(stroke
				(width 0.15)
				(type solid)
			)
			(fill none)
			(layer "B.Fab")
		)
		(fp_text user "Author: Antmicro"
			(at -1.682 -4.894 0)
			(layer "B.Fab")
			(hide yes)
			(effects
				(font
					(size 0.7 0.7)
					(thickness 0.15)
				)
				(justify left bottom mirror)
			)
		)
		(fp_text user "License: Apache-2.0"
			(at -1.682 -5.895 0)
			(layer "B.Fab")
			(hide yes)
			(effects
				(font
					(size 0.7 0.7)
					(thickness 0.15)
				)
				(justify left bottom mirror)
			)
		)
		(fp_text user "${REFERENCE}"
			(at -1.682 -3.895 0)
			(layer "B.Fab")
			(hide yes)
			(effects
				(font
					(size 0.7 0.7)
					(thickness 0.15)
				)
				(justify left bottom mirror)
			)
		)
		(pad "1" smd roundrect
			(at -0.7 0 180)
			(size 0.8 1)
			(layers "B.Cu" "B.Paste" "B.Mask")
			(roundrect_rratio 0.2)
			(net 635 "/M.2/3V3_M2")
			(pintype "passive")
		)
		(pad "2" smd roundrect
			(at 0.7 0 180)
			(size 0.8 1)
			(layers "B.Cu" "B.Paste" "B.Mask")
			(roundrect_rratio 0.2)
			(net 1 "GND")
			(pintype "passive")
		)
	)
	(footprint "antmicro-footprints:R_0402_1005Metric"
		(layer "B.Cu")
		(at 60.55 124.8 -90)
		(descr "Resistor SMD 0402")
		(tags "resistor SMD 0402")
		(property "Reference" "R105"
			(at -1.83 -1.39 90)
			(layer "B.SilkS")
			(effects
				(font
					(size 0.7 0.7)
					(thickness 0.15)
				)
				(justify left bottom mirror)
			)
		)
		(property "Value" "R_4k7_0402"
			(at 0 -1.4 90)
			(layer "B.Fab")
			(effects
				(font
					(size 0.7 0.7)
					(thickness 0.15)
				)
				(justify left bottom mirror)
			)
		)
		(property "Footprint" "antmicro-footprints:R_0402_1005Metric"
			(at 0 0 -90)
			(layer "F.Fab")
			(hide yes)
			(effects
				(font
					(size 1.27 1.27)
					(thickness 0.15)
				)
			)
		)
		(property "Datasheet" "https://www.bourns.com/docs/product-datasheets/cr.pdf"
			(at 0 0 -90)
			(layer "F.Fab")
			(hide yes)
			(effects
				(font
					(size 1.27 1.27)
					(thickness 0.15)
				)
			)
		)
		(property "Author" "Antmicro"
			(at -64.25 185.35 0)
			(layer "B.Fab")
			(hide yes)
			(effects
				(font
					(size 1 1)
					(thickness 0.15)
				)
				(justify mirror)
			)
		)
		(property "License" "Apache-2.0"
			(at -64.25 185.35 0)
			(layer "B.Fab")
			(hide yes)
			(effects
				(font
					(size 1 1)
					(thickness 0.15)
				)
				(justify mirror)
			)
		)
		(property "MPN" "CR0402-FX-4701GLF"
			(at -64.25 185.35 0)
			(layer "B.Fab")
			(hide yes)
			(effects
				(font
					(size 1 1)
					(thickness 0.15)
				)
				(justify mirror)
			)
		)
		(property "Manufacturer" "Bourns"
			(at -64.25 185.35 0)
			(layer "B.Fab")
			(hide yes)
			(effects
				(font
					(size 1 1)
					(thickness 0.15)
				)
				(justify mirror)
			)
		)
		(property "Tolerance" "1%"
			(at -64.25 185.35 0)
			(layer "B.Fab")
			(hide yes)
			(effects
				(font
					(size 1 1)
					(thickness 0.15)
				)
				(justify mirror)
			)
		)
		(property "Val" "4k7"
			(at -64.25 185.35 0)
			(layer "B.Fab")
			(hide yes)
			(effects
				(font
					(size 1 1)
					(thickness 0.15)
				)
				(justify mirror)
			)
		)
		(sheetname "USB Debug, DP")
		(sheetfile "usb.kicad_sch")
		(attr smd)
		(fp_rect
			(start -0.925 0.47)
			(end 0.925 -0.47)
			(stroke
				(width 0.05)
				(type default)
			)
			(fill none)
			(layer "B.CrtYd")
		)
		(fp_rect
			(start -0.5 0.25)
			(end 0.5 -0.25)
			(stroke
				(width 0.15)
				(type solid)
			)
			(fill none)
			(layer "B.Fab")
		)
		(fp_text user "${REFERENCE}"
			(at -0.95 -3.168 90)
			(layer "B.Fab")
			(hide yes)
			(effects
				(font
					(size 0.7 0.7)
					(thickness 0.15)
				)
				(justify left bottom mirror)
			)
		)
		(fp_text user "License: Apache-2.0"
			(at -0.95 -5.169 90)
			(layer "B.Fab")
			(hide yes)
			(effects
				(font
					(size 0.7 0.7)
					(thickness 0.15)
				)
				(justify left bottom mirror)
			)
		)
		(fp_text user "Author: Antmicro"
			(at -0.95 -4.169 90)
			(layer "B.Fab")
			(hide yes)
			(effects
				(font
					(size 0.7 0.7)
					(thickness 0.15)
				)
				(justify left bottom mirror)
			)
		)
		(pad "1" smd roundrect
			(at -0.48 0 270)
			(size 0.59 0.64)
			(layers "B.Cu" "B.Paste" "B.Mask")
			(roundrect_rratio 0.25)
			(net 196 "/USB Debug, DP/USBC3_VBUS")
			(pintype "passive")
		)
		(pad "2" smd roundrect
			(at 0.48 0 270)
			(size 0.59 0.64)
			(layers "B.Cu" "B.Paste" "B.Mask")
			(roundrect_rratio 0.25)
			(net 146 "Net-(D8-A)")
			(pintype "passive")
		)
	)
	(footprint "antmicro-footprints:R_0402_1005Metric"
		(layer "B.Cu")
		(at 52.3 90.95)
		(descr "Resistor SMD 0402")
		(tags "resistor SMD 0402")
		(property "Reference" "R146"
			(at 1.39 1.1 180)
			(layer "B.SilkS")
			(effects
				(font
					(size 0.6 0.6)
					(thickness 0.15)
				)
				(justify left bottom mirror)
			)
		)
		(property "Value" "R_24k9_0402"
			(at 0 -1.4 180)
			(layer "B.Fab")
			(effects
				(font
					(size 0.7 0.7)
					(thickness 0.15)
				)
				(justify left bottom mirror)
			)
		)
		(property "Footprint" "antmicro-footprints:R_0402_1005Metric"
			(at 0 0 0)
			(layer "F.Fab")
			(hide yes)
			(effects
				(font
					(size 1.27 1.27)
					(thickness 0.15)
				)
			)
		)
		(property "Datasheet" "https://www.bourns.com/docs/product-datasheets/cr.pdf"
			(at 0 0 0)
			(layer "F.Fab")
			(hide yes)
			(effects
				(font
					(size 1.27 1.27)
					(thickness 0.15)
				)
			)
		)
		(property "Author" "Antmicro"
			(at 0 0 0)
			(layer "B.Fab")
			(hide yes)
			(effects
				(font
					(size 1 1)
					(thickness 0.15)
				)
				(justify mirror)
			)
		)
		(property "License" "Apache-2.0"
			(at 0 0 0)
			(layer "B.Fab")
			(hide yes)
			(effects
				(font
					(size 1 1)
					(thickness 0.15)
				)
				(justify mirror)
			)
		)
		(property "MPN" "CR0402-FX-2492GLF"
			(at 0 0 0)
			(layer "B.Fab")
			(hide yes)
			(effects
				(font
					(size 1 1)
					(thickness 0.15)
				)
				(justify mirror)
			)
		)
		(property "Manufacturer" "Bourns"
			(at 0 0 0)
			(layer "B.Fab")
			(hide yes)
			(effects
				(font
					(size 1 1)
					(thickness 0.15)
				)
				(justify mirror)
			)
		)
		(property "Tolerance" "1%"
			(at 0 0 0)
			(layer "B.Fab")
			(hide yes)
			(effects
				(font
					(size 1 1)
					(thickness 0.15)
				)
				(justify mirror)
			)
		)
		(property "Val" "24k9"
			(at 0 0 0)
			(layer "B.Fab")
			(hide yes)
			(effects
				(font
					(size 1 1)
					(thickness 0.15)
				)
				(justify mirror)
			)
		)
		(sheetname "Ethernet")
		(sheetfile "ethernet.kicad_sch")
		(attr smd)
		(fp_rect
			(start -0.925 0.47)
			(end 0.925 -0.47)
			(stroke
				(width 0.05)
				(type default)
			)
			(fill none)
			(layer "B.CrtYd")
		)
		(fp_rect
			(start -0.5 0.25)
			(end 0.5 -0.25)
			(stroke
				(width 0.15)
				(type solid)
			)
			(fill none)
			(layer "B.Fab")
		)
		(fp_text user "Author: Antmicro"
			(at -0.95 -4.169 180)
			(layer "B.Fab")
			(hide yes)
			(effects
				(font
					(size 0.7 0.7)
					(thickness 0.15)
				)
				(justify left bottom mirror)
			)
		)
		(fp_text user "${REFERENCE}"
			(at -0.95 -3.168 180)
			(layer "B.Fab")
			(hide yes)
			(effects
				(font
					(size 0.7 0.7)
					(thickness 0.15)
				)
				(justify left bottom mirror)
			)
		)
		(fp_text user "License: Apache-2.0"
			(at -0.95 -5.169 180)
			(layer "B.Fab")
			(hide yes)
			(effects
				(font
					(size 0.7 0.7)
					(thickness 0.15)
				)
				(justify left bottom mirror)
			)
		)
		(pad "1" smd roundrect
			(at -0.48 0)
			(size 0.59 0.64)
			(layers "B.Cu" "B.Paste" "B.Mask")
			(roundrect_rratio 0.25)
			(net 570 "/Ethernet/DEN")
			(pintype "passive")
		)
		(pad "2" smd roundrect
			(at 0.48 0)
			(size 0.59 0.64)
			(layers "B.Cu" "B.Paste" "B.Mask")
			(roundrect_rratio 0.25)
			(net 105 "/Ethernet/VDD")
			(pintype "passive")
		)
	)
	(footprint "antmicro-footprints:R_0402_1005Metric"
		(layer "B.Cu")
		(at 75 108.3 90)
		(descr "Resistor SMD 0402")
		(tags "resistor SMD 0402")
		(property "Reference" "R98"
			(at -0.63 2.37 -90)
			(layer "B.SilkS")
			(effects
				(font
					(size 0.7 0.7)
					(thickness 0.15)
				)
				(justify left bottom mirror)
			)
		)
		(property "Value" "R_1k_0402"
			(at 0 -1.4 -90)
			(layer "B.Fab")
			(effects
				(font
					(size 0.7 0.7)
					(thickness 0.15)
				)
				(justify left bottom mirror)
			)
		)
		(property "Footprint" "antmicro-footprints:R_0402_1005Metric"
			(at 0 0 90)
			(layer "F.Fab")
			(hide yes)
			(effects
				(font
					(size 1.27 1.27)
					(thickness 0.15)
				)
			)
		)
		(property "Datasheet" "https://www.bourns.com/docs/product-datasheets/cr.pdf"
			(at 0 0 90)
			(layer "F.Fab")
			(hide yes)
			(effects
				(font
					(size 1.27 1.27)
					(thickness 0.15)
				)
			)
		)
		(property "Author" "Antmicro"
			(at 183.3 33.3 0)
			(layer "B.Fab")
			(hide yes)
			(effects
				(font
					(size 1 1)
					(thickness 0.15)
				)
				(justify mirror)
			)
		)
		(property "License" "Apache-2.0"
			(at 183.3 33.3 0)
			(layer "B.Fab")
			(hide yes)
			(effects
				(font
					(size 1 1)
					(thickness 0.15)
				)
				(justify mirror)
			)
		)
		(property "MPN" "CR0402-FX-1001GLF"
			(at 183.3 33.3 0)
			(layer "B.Fab")
			(hide yes)
			(effects
				(font
					(size 1 1)
					(thickness 0.15)
				)
				(justify mirror)
			)
		)
		(property "Manufacturer" "Bourns"
			(at 183.3 33.3 0)
			(layer "B.Fab")
			(hide yes)
			(effects
				(font
					(size 1 1)
					(thickness 0.15)
				)
				(justify mirror)
			)
		)
		(property "Tolerance" "1%"
			(at 183.3 33.3 0)
			(layer "B.Fab")
			(hide yes)
			(effects
				(font
					(size 1 1)
					(thickness 0.15)
				)
				(justify mirror)
			)
		)
		(property "Val" "1k"
			(at 183.3 33.3 0)
			(layer "B.Fab")
			(hide yes)
			(effects
				(font
					(size 1 1)
					(thickness 0.15)
				)
				(justify mirror)
			)
		)
		(sheetname "USB Debug, DP")
		(sheetfile "usb.kicad_sch")
		(attr smd)
		(fp_rect
			(start -0.925 0.47)
			(end 0.925 -0.47)
			(stroke
				(width 0.05)
				(type default)
			)
			(fill none)
			(layer "B.CrtYd")
		)
		(fp_rect
			(start -0.5 0.25)
			(end 0.5 -0.25)
			(stroke
				(width 0.15)
				(type solid)
			)
			(fill none)
			(layer "B.Fab")
		)
		(fp_text user "${REFERENCE}"
			(at -0.95 -3.168 -90)
			(layer "B.Fab")
			(hide yes)
			(effects
				(font
					(size 0.7 0.7)
					(thickness 0.15)
				)
				(justify left bottom mirror)
			)
		)
		(fp_text user "License: Apache-2.0"
			(at -0.95 -5.169 -90)
			(layer "B.Fab")
			(hide yes)
			(effects
				(font
					(size 0.7 0.7)
					(thickness 0.15)
				)
				(justify left bottom mirror)
			)
		)
		(fp_text user "Author: Antmicro"
			(at -0.95 -4.169 -90)
			(layer "B.Fab")
			(hide yes)
			(effects
				(font
					(size 0.7 0.7)
					(thickness 0.15)
				)
				(justify left bottom mirror)
			)
		)
		(pad "1" smd roundrect
			(at -0.48 0 90)
			(size 0.59 0.64)
			(layers "B.Cu" "B.Paste" "B.Mask")
			(roundrect_rratio 0.25)
			(net 310 "/USB Debug, DP/USBC0_EQ1")
			(pintype "passive")
		)
		(pad "2" smd roundrect
			(at 0.48 0 90)
			(size 0.59 0.64)
			(layers "B.Cu" "B.Paste" "B.Mask")
			(roundrect_rratio 0.25)
			(net 1 "GND")
			(pintype "passive")
		)
	)
)
